(kicad_pcb
	(version 20241229)
	(generator "pcbnew")
	(generator_version "9.0")
	(general
		(thickness 1.711)
		(legacy_teardrops no)
	)
	(paper "A4")
	(title_block
		(title "Antmicro Baseboard for Jetson AGX Thor")
		(date "2026-02-18")
		(rev "1.1.0")
		(company "Antmicro Ltd")
		(comment 1 "www.antmicro.com")
		(comment 9 "footprints 809-814 of 1170")
	)
	(layers
		(0 "F.Cu" signal)
		(4 "In1.Cu" signal)
		(6 "In2.Cu" signal)
		(8 "In3.Cu" signal)
		(10 "In4.Cu" jumper)
		(12 "In5.Cu" signal)
		(14 "In6.Cu" signal)
		(16 "In7.Cu" signal)
		(18 "In8.Cu" signal)
		(2 "B.Cu" signal)
		(9 "F.Adhes" user "F.Adhesive")
		(11 "B.Adhes" user "B.Adhesive")
		(13 "F.Paste" user)
		(15 "B.Paste" user)
		(5 "F.SilkS" user "F.Silkscreen")
		(7 "B.SilkS" user "B.Silkscreen")
		(1 "F.Mask" user)
		(3 "B.Mask" user)
		(17 "Dwgs.User" user "User.Drawings")
		(19 "Cmts.User" user "User.Comments")
		(21 "Eco1.User" user "User.Eco1")
		(23 "Eco2.User" user "User.Eco2")
		(25 "Edge.Cuts" user)
		(27 "Margin" user)
		(31 "F.CrtYd" user "F.Courtyard")
		(29 "B.CrtYd" user "B.Courtyard")
		(35 "F.Fab" user)
		(33 "B.Fab" user)
	)
	(footprint "antmicro-footprints:R_0402_1005Metric"
		(layer "B.Cu")
		(at 109.82 133.3)
		(descr "Resistor SMD 0402")
		(tags "resistor SMD 0402")
		(property "Reference" "R215"
			(at -3.82 -0.24 0)
			(layer "B.SilkS")
			(effects
				(font
					(size 0.7 0.7)
					(thickness 0.15)
				)
				(justify right top mirror)
			)
		)
		(property "Value" "R_0R_0402"
			(at -1.011843 -1.772047 0)
			(layer "B.Fab")
			(effects
				(font
					(size 0.7 0.7)
					(thickness 0.15)
				)
				(justify right top mirror)
			)
		)
		(property "Datasheet" "https://industrial.panasonic.com/cdbs/www-data/pdf/RDA0000/AOA0000C301.pdf"
			(at 0 0 0)
			(layer "B.Fab")
			(hide yes)
			(effects
				(font
					(size 1.27 1.27)
					(thickness 0.15)
				)
				(justify mirror)
			)
		)
		(property "Description" "SMD Chip Resistor, Jumper, 0 ohm, 100 mW, 0402 [1005 Metric], Thick Film, General Purpose"
			(at 0 0 0)
			(layer "B.Fab")
			(hide yes)
			(effects
				(font
					(size 1.27 1.27)
					(thickness 0.15)
				)
				(justify mirror)
			)
		)
		(property "MPN" "ERJ2GE0R00X"
			(at 0 0 180)
			(unlocked yes)
			(layer "B.Fab")
			(hide yes)
			(effects
				(font
					(size 1 1)
					(thickness 0.15)
				)
				(justify mirror)
			)
		)
		(property "Manufacturer" "Panasonic"
			(at 0 0 180)
			(unlocked yes)
			(layer "B.Fab")
			(hide yes)
			(effects
				(font
					(size 1 1)
					(thickness 0.15)
				)
				(justify mirror)
			)
		)
		(property "License" "Apache-2.0"
			(at 0 0 180)
			(unlocked yes)
			(layer "B.Fab")
			(hide yes)
			(effects
				(font
					(size 1 1)
					(thickness 0.15)
				)
				(justify mirror)
			)
		)
		(property "Author" "Antmicro"
			(at 0 0 180)
			(unlocked yes)
			(layer "B.Fab")
			(hide yes)
			(effects
				(font
					(size 1 1)
					(thickness 0.15)
				)
				(justify mirror)
			)
		)
		(property "Val" "0R"
			(at 0 0 180)
			(unlocked yes)
			(layer "B.Fab")
			(hide yes)
			(effects
				(font
					(size 1 1)
					(thickness 0.15)
				)
				(justify mirror)
			)
		)
		(property "Tolerance" "~"
			(at 0 0 180)
			(unlocked yes)
			(layer "B.Fab")
			(hide yes)
			(effects
				(font
					(size 1 1)
					(thickness 0.15)
				)
				(justify mirror)
			)
		)
		(property "Current" "1A"
			(at 0 0 180)
			(unlocked yes)
			(layer "B.Fab")
			(hide yes)
			(effects
				(font
					(size 1 1)
					(thickness 0.15)
				)
				(justify mirror)
			)
		)
		(sheetname "/M.2/")
		(sheetfile "m2.kicad_sch")
		(attr smd)
		(fp_rect
			(start -0.925 0.47)
			(end 0.925 -0.47)
			(stroke
				(width 0.05)
				(type default)
			)
			(fill no)
			(layer "B.CrtYd")
		)
		(fp_rect
			(start -0.5 0.25)
			(end 0.5 -0.25)
			(stroke
				(width 0.15)
				(type solid)
			)
			(fill no)
			(layer "B.Fab")
		)
		(fp_text user "Author: Antmicro"
			(at -0.95 -4.169 0)
			(layer "B.Fab")
			(effects
				(font
					(size 0.7 0.7)
					(thickness 0.15)
				)
				(justify right top mirror)
			)
		)
		(fp_text user "License: Apache-2.0"
			(at -0.95 -5.169 0)
			(layer "B.Fab")
			(effects
				(font
					(size 0.7 0.7)
					(thickness 0.15)
				)
				(justify right top mirror)
			)
		)
		(fp_text user "${REFERENCE}"
			(at -0.95 -3.168 0)
			(layer "B.Fab")
			(effects
				(font
					(size 0.7 0.7)
					(thickness 0.15)
				)
				(justify right top mirror)
			)
		)
		(pad "1" smd roundrect
			(at -0.48 0)
			(size 0.59 0.64)
			(layers "B.Cu" "B.Mask" "B.Paste")
			(roundrect_rratio 0.25)
			(net 137 "/M.2/PCIe_{C1x1}.~{CLKREQ}")
			(pintype "passive")
		)
		(pad "2" smd roundrect
			(at 0.48 0)
			(size 0.59 0.64)
			(layers "B.Cu" "B.Mask" "B.Paste")
			(roundrect_rratio 0.25)
			(net 834 "/M.2/~{CLKREQ_E}")
			(pintype "passive")
		)
	)
	(footprint "antmicro-footprints:R_0402_1005Metric"
		(layer "B.Cu")
		(at 168.5 57.5 -90)
		(descr "Resistor SMD 0402")
		(tags "resistor SMD 0402")
		(property "Reference" "R32"
			(at -3.58 -0.315532 90)
			(layer "B.SilkS")
			(effects
				(font
					(size 0.7 0.7)
					(thickness 0.15)
				)
				(justify left bottom mirror)
			)
		)
		(property "Value" "R_200R_0402"
			(at -1.011843 -1.772047 90)
			(layer "B.Fab")
			(effects
				(font
					(size 0.7 0.7)
					(thickness 0.15)
				)
				(justify left bottom mirror)
			)
		)
		(property "Datasheet" "https://www.bourns.com/docs/product-datasheets/cr.pdf"
			(at 0 0 90)
			(layer "B.Fab")
			(hide yes)
			(effects
				(font
					(size 1.27 1.27)
					(thickness 0.15)
				)
				(justify mirror)
			)
		)
		(property "Description" "SMD Chip Resistor, 200 ohm, ± 1%, 62.5 mW, 0402 [1005 Metric], Thick Film, General Purpose"
			(at 0 0 90)
			(layer "B.Fab")
			(hide yes)
			(effects
				(font
					(size 1.27 1.27)
					(thickness 0.15)
				)
				(justify mirror)
			)
		)
		(property "Manufacturer" "Bourns"
			(at 0 0 90)
			(unlocked yes)
			(layer "B.Fab")
			(hide yes)
			(effects
				(font
					(size 1 1)
					(thickness 0.15)
				)
				(justify mirror)
			)
		)
		(property "MPN" "CR0402-FX-2000GLF"
			(at 0 0 90)
			(unlocked yes)
			(layer "B.Fab")
			(hide yes)
			(effects
				(font
					(size 1 1)
					(thickness 0.15)
				)
				(justify mirror)
			)
		)
		(property "Val" "200R"
			(at 0 0 90)
			(unlocked yes)
			(layer "B.Fab")
			(hide yes)
			(effects
				(font
					(size 1 1)
					(thickness 0.15)
				)
				(justify mirror)
			)
		)
		(property "License" "Apache-2.0"
			(at 0 0 90)
			(unlocked yes)
			(layer "B.Fab")
			(hide yes)
			(effects
				(font
					(size 1 1)
					(thickness 0.15)
				)
				(justify mirror)
			)
		)
		(property "Author" "Antmicro"
			(at 0 0 90)
			(unlocked yes)
			(layer "B.Fab")
			(hide yes)
			(effects
				(font
					(size 1 1)
					(thickness 0.15)
				)
				(justify mirror)
			)
		)
		(property "Tolerance" "1%"
			(at 0 0 90)
			(unlocked yes)
			(layer "B.Fab")
			(hide yes)
			(effects
				(font
					(size 1 1)
					(thickness 0.15)
				)
				(justify mirror)
			)
		)
		(sheetname "/Power/")
		(sheetfile "power.kicad_sch")
		(attr smd)
		(fp_rect
			(start -0.925 0.47)
			(end 0.925 -0.47)
			(stroke
				(width 0.05)
				(type default)
			)
			(fill no)
			(layer "B.CrtYd")
		)
		(fp_rect
			(start -0.5 0.25)
			(end 0.5 -0.25)
			(stroke
				(width 0.15)
				(type solid)
			)
			(fill no)
			(layer "B.Fab")
		)
		(fp_text user "License: Apache-2.0"
			(at -0.95 -5.169 90)
			(layer "B.Fab")
			(effects
				(font
					(size 0.7 0.7)
					(thickness 0.15)
				)
				(justify left bottom mirror)
			)
		)
		(fp_text user "Author: Antmicro"
			(at -0.95 -4.169 90)
			(layer "B.Fab")
			(effects
				(font
					(size 0.7 0.7)
					(thickness 0.15)
				)
				(justify left bottom mirror)
			)
		)
		(fp_text user "${REFERENCE}"
			(at -0.95 -3.168 90)
			(layer "B.Fab")
			(effects
				(font
					(size 0.7 0.7)
					(thickness 0.15)
				)
				(justify left bottom mirror)
			)
		)
		(pad "1" smd roundrect
			(at -0.48 0 270)
			(size 0.59 0.64)
			(layers "B.Cu" "B.Mask" "B.Paste")
			(roundrect_rratio 0.25)
			(net 526 "Net-(D3-A)")
			(pintype "passive")
		)
		(pad "2" smd roundrect
			(at 0.48 0 270)
			(size 0.59 0.64)
			(layers "B.Cu" "B.Mask" "B.Paste")
			(roundrect_rratio 0.25)
			(net 4 "+3V3_AON")
			(pintype "passive")
		)
	)
	(footprint "antmicro-footprints:TP_SMD_0.75mm"
		(layer "B.Cu")
		(at 178.61 58 -90)
		(property "Reference" "TP125"
			(at -4.04 -0.43 90)
			(layer "B.SilkS")
			(effects
				(font
					(size 0.7 0.7)
					(thickness 0.15)
				)
				(justify left bottom mirror)
			)
		)
		(property "Value" "TP_0.75mm_SMD"
			(at 0 -1.2 90)
			(layer "B.Fab")
			(effects
				(font
					(size 0.7 0.7)
					(thickness 0.15)
				)
				(justify left bottom mirror)
			)
		)
		(property "Description" "SMT test point"
			(at 0 0 90)
			(layer "B.Fab")
			(hide yes)
			(effects
				(font
					(size 1.27 1.27)
					(thickness 0.15)
				)
				(justify mirror)
			)
		)
		(property "MPN" ""
			(at 0 0 90)
			(unlocked yes)
			(layer "B.Fab")
			(hide yes)
			(effects
				(font
					(size 1 1)
					(thickness 0.15)
				)
				(justify mirror)
			)
		)
		(property "Manufacturer" ""
			(at 0 0 90)
			(unlocked yes)
			(layer "B.Fab")
			(hide yes)
			(effects
				(font
					(size 1 1)
					(thickness 0.15)
				)
				(justify mirror)
			)
		)
		(property "Author" "Antmicro"
			(at 0 0 90)
			(unlocked yes)
			(layer "B.Fab")
			(hide yes)
			(effects
				(font
					(size 1 1)
					(thickness 0.15)
				)
				(justify mirror)
			)
		)
		(property "License" "Apache-2.0"
			(at 0 0 90)
			(unlocked yes)
			(layer "B.Fab")
			(hide yes)
			(effects
				(font
					(size 1 1)
					(thickness 0.15)
				)
				(justify mirror)
			)
		)
		(sheetname "/Power/")
		(sheetfile "power.kicad_sch")
		(attr exclude_from_pos_files exclude_from_bom)
		(fp_circle
			(center 0 0)
			(end 0.475 0)
			(stroke
				(width 0.05)
				(type default)
			)
			(fill no)
			(layer "B.CrtYd")
		)
		(fp_text user "Author: Antmicro"
			(at -0.4 -3.901 90)
			(layer "B.Fab")
			(effects
				(font
					(size 0.7 0.7)
					(thickness 0.15)
				)
				(justify left bottom mirror)
			)
		)
		(fp_text user "${REFERENCE}"
			(at -0.4 -2.7 90)
			(layer "B.Fab")
			(effects
				(font
					(size 0.7 0.7)
					(thickness 0.15)
				)
				(justify left bottom mirror)
			)
		)
		(fp_text user "License: Apache-2.0"
			(at -0.4 -5.101 90)
			(layer "B.Fab")
			(effects
				(font
					(size 0.7 0.7)
					(thickness 0.15)
				)
				(justify left bottom mirror)
			)
		)
		(pad "1" smd circle
			(at 0 0 270)
			(size 0.75 0.75)
			(layers "B.Cu" "B.Mask")
			(net 634 "+12V")
			(pinfunction "1")
			(pintype "passive")
		)
	)
	(footprint "antmicro-footprints:TP_SMD_0.75mm"
		(layer "B.Cu")
		(at 124.5 72.6 90)
		(property "Reference" "TP51"
			(at -3.2 -0.3 90)
			(layer "B.SilkS")
			(effects
				(font
					(size 0.7 0.7)
					(thickness 0.15)
				)
				(justify right top mirror)
			)
		)
		(property "Value" "TP_0.75mm_SMD"
			(at 0 -1.2 90)
			(layer "B.Fab")
			(effects
				(font
					(size 0.7 0.7)
					(thickness 0.15)
				)
				(justify right top mirror)
			)
		)
		(property "Description" "SMT test point"
			(at 0 0 90)
			(layer "B.Fab")
			(hide yes)
			(effects
				(font
					(size 1.27 1.27)
					(thickness 0.15)
				)
				(justify mirror)
			)
		)
		(property "MPN" ""
			(at 0 0 270)
			(unlocked yes)
			(layer "B.Fab")
			(hide yes)
			(effects
				(font
					(size 1 1)
					(thickness 0.15)
				)
				(justify mirror)
			)
		)
		(property "Manufacturer" ""
			(at 0 0 270)
			(unlocked yes)
			(layer "B.Fab")
			(hide yes)
			(effects
				(font
					(size 1 1)
					(thickness 0.15)
				)
				(justify mirror)
			)
		)
		(property "Author" "Antmicro"
			(at 0 0 270)
			(unlocked yes)
			(layer "B.Fab")
			(hide yes)
			(effects
				(font
					(size 1 1)
					(thickness 0.15)
				)
				(justify mirror)
			)
		)
		(property "License" "Apache-2.0"
			(at 0 0 270)
			(unlocked yes)
			(layer "B.Fab")
			(hide yes)
			(effects
				(font
					(size 1 1)
					(thickness 0.15)
				)
				(justify mirror)
			)
		)
		(sheetname "/SoM_Power/")
		(sheetfile "som_power.kicad_sch")
		(attr exclude_from_pos_files exclude_from_bom)
		(fp_circle
			(center 0 0)
			(end 0.475 0)
			(stroke
				(width 0.05)
				(type default)
			)
			(fill no)
			(layer "B.CrtYd")
		)
		(fp_text user "${REFERENCE}"
			(at -0.4 -2.7 90)
			(layer "B.Fab")
			(effects
				(font
					(size 0.7 0.7)
					(thickness 0.15)
				)
				(justify right top mirror)
			)
		)
		(fp_text user "Author: Antmicro"
			(at -0.4 -3.901 90)
			(layer "B.Fab")
			(effects
				(font
					(size 0.7 0.7)
					(thickness 0.15)
				)
				(justify right top mirror)
			)
		)
		(fp_text user "License: Apache-2.0"
			(at -0.4 -5.101 90)
			(layer "B.Fab")
			(effects
				(font
					(size 0.7 0.7)
					(thickness 0.15)
				)
				(justify right top mirror)
			)
		)
		(pad "1" smd circle
			(at 0 0 90)
			(size 0.75 0.75)
			(layers "B.Cu" "B.Mask")
			(net 762 "Net-(J1A-SYSTEM_OC_N)")
			(pinfunction "1")
			(pintype "passive")
		)
	)
	(footprint "antmicro-footprints:TP_SMD_0.75mm"
		(layer "B.Cu")
		(at 98.15 69.7 -90)
		(property "Reference" "TP99"
			(at 0 0.6 90)
			(layer "B.SilkS")
			(effects
				(font
					(size 0.7 0.7)
					(thickness 0.15)
				)
				(justify left bottom mirror)
			)
		)
		(property "Value" "TP_0.75mm_SMD"
			(at 0 -1.2 90)
			(layer "B.Fab")
			(effects
				(font
					(size 0.7 0.7)
					(thickness 0.15)
				)
				(justify left bottom mirror)
			)
		)
		(property "Description" "SMT test point"
			(at 0 0 90)
			(layer "B.Fab")
			(hide yes)
			(effects
				(font
					(size 1.27 1.27)
					(thickness 0.15)
				)
				(justify mirror)
			)
		)
		(property "MPN" ""
			(at 0 0 90)
			(unlocked yes)
			(layer "B.Fab")
			(hide yes)
			(effects
				(font
					(size 1 1)
					(thickness 0.15)
				)
				(justify mirror)
			)
		)
		(property "Manufacturer" ""
			(at 0 0 90)
			(unlocked yes)
			(layer "B.Fab")
			(hide yes)
			(effects
				(font
					(size 1 1)
					(thickness 0.15)
				)
				(justify mirror)
			)
		)
		(property "Author" "Antmicro"
			(at 0 0 90)
			(unlocked yes)
			(layer "B.Fab")
			(hide yes)
			(effects
				(font
					(size 1 1)
					(thickness 0.15)
				)
				(justify mirror)
			)
		)
		(property "License" "Apache-2.0"
			(at 0 0 90)
			(unlocked yes)
			(layer "B.Fab")
			(hide yes)
			(effects
				(font
					(size 1 1)
					(thickness 0.15)
				)
				(justify mirror)
			)
		)
		(sheetname "/SoM_IO/")
		(sheetfile "som_io.kicad_sch")
		(attr exclude_from_pos_files exclude_from_bom)
		(fp_circle
			(center 0 0)
			(end 0.475 0)
			(stroke
				(width 0.05)
				(type default)
			)
			(fill no)
			(layer "B.CrtYd")
		)
		(fp_text user "License: Apache-2.0"
			(at -0.4 -5.101 90)
			(layer "B.Fab")
			(effects
				(font
					(size 0.7 0.7)
					(thickness 0.15)
				)
				(justify left bottom mirror)
			)
		)
		(fp_text user "${REFERENCE}"
			(at -0.4 -2.7 90)
			(layer "B.Fab")
			(effects
				(font
					(size 0.7 0.7)
					(thickness 0.15)
				)
				(justify left bottom mirror)
			)
		)
		(fp_text user "Author: Antmicro"
			(at -0.4 -3.901 90)
			(layer "B.Fab")
			(effects
				(font
					(size 0.7 0.7)
					(thickness 0.15)
				)
				(justify left bottom mirror)
			)
		)
		(pad "1" smd circle
			(at 0 0 270)
			(size 0.75 0.75)
			(layers "B.Cu" "B.Mask")
			(net 107 "/SoM_IO/I2S_{M.2}.CLK")
			(pinfunction "1")
			(pintype "passive")
		)
	)
	(footprint "antmicro-footprints:C_0805_2012Metric"
		(layer "B.Cu")
		(at 229.1 95.1 90)
		(descr "Capacitor SMD 0805")
		(tags "capacitor SMD 0805")
		(property "Reference" "C68"
			(at -3.8 0.6 90)
			(layer "B.SilkS")
			(effects
				(font
					(size 0.7 0.7)
					(thickness 0.15)
				)
				(justify right top mirror)
			)
		)
		(property "Value" "C_22u_25V_0805"
			(at -2.055717 -1.963153 90)
			(layer "B.Fab")
			(effects
				(font
					(size 0.7 0.7)
					(thickness 0.15)
				)
				(justify right top mirror)
			)
		)
		(property "Datasheet" "https://product.samsungsem.com/mlcc/CL21A226MAYNNN.do"
			(at 0 0 90)
			(layer "B.Fab")
			(hide yes)
			(effects
				(font
					(size 1.27 1.27)
					(thickness 0.15)
				)
				(justify mirror)
			)
		)
		(property "Description" "SMT Multilayer Ceramic Capacitor, 22uF, +/-20%, 25V, X5R, 0805 [2012 Metric]"
			(at 0 0 90)
			(layer "B.Fab")
			(hide yes)
			(effects
				(font
					(size 1.27 1.27)
					(thickness 0.15)
				)
				(justify mirror)
			)
		)
		(property "Manufacturer" "Samsung Electro-Mechanics"
			(at 0 0 90)
			(unlocked yes)
			(layer "B.Fab")
			(hide yes)
			(effects
				(font
					(size 1 1)
					(thickness 0.15)
				)
				(justify mirror)
			)
		)
		(property "MPN" "CL21A226MAYNNNE"
			(at 0 0 90)
			(unlocked yes)
			(layer "B.Fab")
			(hide yes)
			(effects
				(font
					(size 1 1)
					(thickness 0.15)
				)
				(justify mirror)
			)
		)
		(property "Val" "22u"
			(at 0 0 90)
			(unlocked yes)
			(layer "B.Fab")
			(hide yes)
			(effects
				(font
					(size 1 1)
					(thickness 0.15)
				)
				(justify mirror)
			)
		)
		(property "License" "Apache-2.0"
			(at 0 0 90)
			(unlocked yes)
			(layer "B.Fab")
			(hide yes)
			(effects
				(font
					(size 1 1)
					(thickness 0.15)
				)
				(justify mirror)
			)
		)
		(property "Author" "Antmicro"
			(at 0 0 90)
			(unlocked yes)
			(layer "B.Fab")
			(hide yes)
			(effects
				(font
					(size 1 1)
					(thickness 0.15)
				)
				(justify mirror)
			)
		)
		(property "Voltage" "25V"
			(at 0 0 90)
			(unlocked yes)
			(layer "B.Fab")
			(hide yes)
			(effects
				(font
					(size 1 1)
					(thickness 0.15)
				)
				(justify mirror)
			)
		)
		(property "Dielectric" "X5R"
			(at 0 0 90)
			(unlocked yes)
			(layer "B.Fab")
			(hide yes)
			(effects
				(font
					(size 1 1)
					(thickness 0.15)
				)
				(justify mirror)
			)
		)
		(property "Public" "False"
			(at 0 0 90)
			(unlocked yes)
			(layer "B.Fab")
			(hide yes)
			(effects
				(font
					(size 1 1)
					(thickness 0.15)
				)
				(justify mirror)
			)
		)
		(sheetname "/USB DP Alt mode/")
		(sheetfile "usb_dp.kicad_sch")
		(attr smd)
		(fp_line
			(start -0.3 -0.7)
			(end 0.3 -0.7)
			(stroke
				(width 0.15)
				(type solid)
			)
			(layer "B.SilkS")
		)
		(fp_line
			(start -0.3 0.7)
			(end 0.3 0.7)
			(stroke
				(width 0.15)
				(type solid)
			)
			(layer "B.SilkS")
		)
		(fp_poly
			(pts
				(xy 1.95 0.9) (xy -1.95 0.9) (xy -1.95 -0.9) (xy 1.95 -0.9)
			)
			(stroke
				(width 0.05)
				(type default)
			)
			(fill no)
			(layer "B.CrtYd")
		)
		(fp_poly
			(pts
				(xy -0.95 0.675001) (xy 0.95 0.675001) (xy 0.95 -0.675001) (xy -0.95 -0.675001)
			)
			(stroke
				(width 0.15)
				(type solid)
			)
			(fill no)
			(layer "B.Fab")
		)
		(fp_text user "Author: Antmicro"
			(at -1.9 -5.947 90)
			(layer "B.Fab")
			(effects
				(font
					(size 0.7 0.7)
					(thickness 0.15)
				)
				(justify right top mirror)
			)
		)
		(fp_text user "${REFERENCE}"
			(at -1.899999 -3.947 90)
			(layer "B.Fab")
			(effects
				(font
					(size 0.7 0.7)
					(thickness 0.15)
				)
				(justify right top mirror)
			)
		)
		(fp_text user "License: Apache-2.0"
			(at -1.9 -4.947 90)
			(layer "B.Fab")
			(effects
				(font
					(size 0.7 0.7)
					(thickness 0.15)
				)
				(justify right top mirror)
			)
		)
		(pad "1" smd roundrect
			(at -1.099999 0 90)
			(size 1.2 1.3)
			(layers "B.Cu" "B.Mask" "B.Paste")
			(roundrect_rratio 0.25)
			(net 376 "/USB DP Alt mode/USBC1_VBUS")
			(pintype "passive")
		)
		(pad "2" smd roundrect
			(at 1.099999 0 90)
			(size 1.2 1.3)
			(layers "B.Cu" "B.Mask" "B.Paste")
			(roundrect_rratio 0.25)
			(net 1 "GND")
			(pintype "passive")
		)
	)
)
